# SCM (Grand Teton) — schematic netlist excerpt (pin names and nets, part order shuffled) for the footprints in the layout excerpt that follows; sources: Cadence DE-HDL packaged netlist, KiCad conversion of 12092022_DA0F0TMDCD0_F0T_Management_Board_D_brd_V3_OCP.brd

R449  Q_RES  33.2 1% CHIP  pkg 0402LF  page 15 : A = SMB_BMC_ALERT10_N ; B = SMB_BMC_ALERT10_R_N
R61  Q_RES  4.7K 1% CHIP  pkg 0402LF  page 13 : A = P3V3_AUX ; B = IRQ_BMC_PCH_NMI_N

(kicad_pcb
	(version 20260206)
	(generator "pcbnew")
	(generator_version "10.0")
	(general
		(thickness 1.6)
		(legacy_teardrops no)
	)
	(paper "A4")
	(title_block
		(title "12092022_DA0F0TMDCD0_F0T_Management_Board_D_brd_V3_OCP.brd")
		(comment 1 "Grand Teton / footprints 1308-1309 of 1440")
	)
	(layers
		(0 "F.Cu" signal "TOP")
		(4 "In1.Cu" signal "GND")
		(6 "In2.Cu" signal "IN1")
		(8 "In3.Cu" signal "GND1")
		(10 "In4.Cu" signal "IN2")
		(12 "In5.Cu" signal "VCC")
		(14 "In6.Cu" signal "VCC1")
		(16 "In7.Cu" signal "IN3")
		(18 "In8.Cu" signal "GND2")
		(20 "In9.Cu" signal "IN4")
		(22 "In10.Cu" signal "GND3")
		(2 "B.Cu" signal "BOTTOM")
		(9 "F.Adhes" user "F.Adhesive")
		(11 "B.Adhes" user "B.Adhesive")
		(13 "F.Paste" user "Package Geometry/Pastemask Top")
		(15 "B.Paste" user "Package Geometry/Pastemask Bottom")
		(5 "F.SilkS" user "Ref Des/Silkscreen Top")
		(7 "B.SilkS" user "Ref Des/Silkscreen Bottom")
		(1 "F.Mask" user "Board Geometry/Soldermask Top")
		(3 "B.Mask" user "Board Geometry/Soldermask Bottom")
		(17 "Dwgs.User" user "User.Drawings")
		(19 "Cmts.User" user "User.Comments")
		(21 "Eco1.User" user "User.Eco1")
		(23 "Eco2.User" user "User.Eco2")
		(25 "Edge.Cuts" user "Board Geometry/Outline")
		(27 "Margin" user)
		(31 "F.CrtYd" user "Package Geometry/Place Bound Top")
		(29 "B.CrtYd" user "Package Geometry/Place Bound Bottom")
		(35 "F.Fab" user "Ref Des/Assembly Top")
		(33 "B.Fab" user "Ref Des/Assembly Bottom")
	)
	(footprint ""
		(layer "B.Cu")
		(at 47.879 -52.1462 -90)
		(property "Reference" "R61"
			(at 0 0 90)
			(layer "B.SilkS")
			(hide yes)
			(effects
				(font
					(size 1.27 1.27)
				)
				(justify mirror)
			)
		)
		(property "Value" ""
			(at 0 0 90)
			(layer "B.Fab")
			(effects
				(font
					(size 1.27 1.27)
				)
				(justify mirror)
			)
		)
		(duplicate_pad_numbers_are_jumpers no)
		(fp_line
			(start -0.7874 0.4064)
			(end 0.7874 0.4064)
			(stroke
				(width 0.1524)
				(type default)
			)
			(layer "B.SilkS")
		)
		(fp_line
			(start 0.7874 0.4064)
			(end 0.7874 -0.4064)
			(stroke
				(width 0.1524)
				(type default)
			)
			(layer "B.SilkS")
		)
		(fp_line
			(start -0.7874 -0.4064)
			(end -0.7874 0.4064)
			(stroke
				(width 0.1524)
				(type default)
			)
			(layer "B.SilkS")
		)
		(fp_line
			(start 0.7874 -0.4064)
			(end -0.7874 -0.4064)
			(stroke
				(width 0.1524)
				(type default)
			)
			(layer "B.SilkS")
		)
		(fp_line
			(start -0.67945 0.3048)
			(end -0.120396 0.3048)
			(stroke
				(width 0.1)
				(type default)
			)
			(layer "B.Fab")
		)
		(fp_line
			(start -0.120396 0.3048)
			(end -0.120396 0.2794)
			(stroke
				(width 0.1)
				(type default)
			)
			(layer "B.Fab")
		)
		(fp_line
			(start 0.12065 0.3048)
			(end 0.67945 0.3048)
			(stroke
				(width 0.1)
				(type default)
			)
			(layer "B.Fab")
		)
		(fp_line
			(start 0.67945 0.3048)
			(end 0.67945 -0.305054)
			(stroke
				(width 0.1)
				(type default)
			)
			(layer "B.Fab")
		)
		(fp_line
			(start -0.120396 0.2794)
			(end 0.12065 0.2794)
			(stroke
				(width 0.1)
				(type default)
			)
			(layer "B.Fab")
		)
		(fp_line
			(start 0.12065 0.2794)
			(end 0.12065 0.3048)
			(stroke
				(width 0.1)
				(type default)
			)
			(layer "B.Fab")
		)
		(fp_line
			(start -0.12065 -0.2794)
			(end -0.12065 -0.3048)
			(stroke
				(width 0.1)
				(type default)
			)
			(layer "B.Fab")
		)
		(fp_line
			(start 0.12065 -0.2794)
			(end -0.12065 -0.2794)
			(stroke
				(width 0.1)
				(type default)
			)
			(layer "B.Fab")
		)
		(fp_line
			(start -0.67945 -0.3048)
			(end -0.67945 0.3048)
			(stroke
				(width 0.1)
				(type default)
			)
			(layer "B.Fab")
		)
		(fp_line
			(start -0.12065 -0.3048)
			(end -0.67945 -0.3048)
			(stroke
				(width 0.1)
				(type default)
			)
			(layer "B.Fab")
		)
		(fp_line
			(start 0.12065 -0.305054)
			(end 0.12065 -0.2794)
			(stroke
				(width 0.1)
				(type default)
			)
			(layer "B.Fab")
		)
		(fp_line
			(start 0.67945 -0.305054)
			(end 0.12065 -0.305054)
			(stroke
				(width 0.1)
				(type default)
			)
			(layer "B.Fab")
		)
		(pad "1" smd circle
			(at 0.40005 0 90)
			(size 0 0)
			(layers "B.Cu" "B.Mask" "B.Paste")
			(net "P3V3_AUX")
		)
		(pad "2" smd circle
			(at -0.40005 0 90)
			(size 0 0)
			(layers "B.Cu" "B.Mask" "B.Paste")
			(net "IRQ_BMC_PCH_NMI_N")
		)
	)
	(footprint ""
		(layer "B.Cu")
		(at 47.879 -63.9445 90)
		(property "Reference" "R449"
			(at 0 0 90)
			(layer "B.SilkS")
			(hide yes)
			(effects
				(font
					(size 1.27 1.27)
				)
				(justify mirror)
			)
		)
		(property "Value" ""
			(at 0 0 90)
			(layer "B.Fab")
			(effects
				(font
					(size 1.27 1.27)
				)
				(justify mirror)
			)
		)
		(duplicate_pad_numbers_are_jumpers no)
		(fp_line
			(start 0.7874 -0.4064)
			(end -0.7874 -0.4064)
			(stroke
				(width 0.1524)
				(type default)
			)
			(layer "B.SilkS")
		)
		(fp_line
			(start -0.7874 -0.4064)
			(end -0.7874 0.4064)
			(stroke
				(width 0.1524)
				(type default)
			)
			(layer "B.SilkS")
		)
		(fp_line
			(start 0.7874 0.4064)
			(end 0.7874 -0.4064)
			(stroke
				(width 0.1524)
				(type default)
			)
			(layer "B.SilkS")
		)
		(fp_line
			(start -0.7874 0.4064)
			(end 0.7874 0.4064)
			(stroke
				(width 0.1524)
				(type default)
			)
			(layer "B.SilkS")
		)
		(fp_line
			(start 0.67945 -0.305054)
			(end 0.12065 -0.305054)
			(stroke
				(width 0.1)
				(type default)
			)
			(layer "B.Fab")
		)
		(fp_line
			(start 0.12065 -0.305054)
			(end 0.12065 -0.2794)
			(stroke
				(width 0.1)
				(type default)
			)
			(layer "B.Fab")
		)
		(fp_line
			(start -0.12065 -0.3048)
			(end -0.67945 -0.3048)
			(stroke
				(width 0.1)
				(type default)
			)
			(layer "B.Fab")
		)
		(fp_line
			(start -0.67945 -0.3048)
			(end -0.67945 0.3048)
			(stroke
				(width 0.1)
				(type default)
			)
			(layer "B.Fab")
		)
		(fp_line
			(start 0.12065 -0.2794)
			(end -0.12065 -0.2794)
			(stroke
				(width 0.1)
				(type default)
			)
			(layer "B.Fab")
		)
		(fp_line
			(start -0.12065 -0.2794)
			(end -0.12065 -0.3048)
			(stroke
				(width 0.1)
				(type default)
			)
			(layer "B.Fab")
		)
		(fp_line
			(start 0.12065 0.2794)
			(end 0.12065 0.3048)
			(stroke
				(width 0.1)
				(type default)
			)
			(layer "B.Fab")
		)
		(fp_line
			(start -0.120396 0.2794)
			(end 0.12065 0.2794)
			(stroke
				(width 0.1)
				(type default)
			)
			(layer "B.Fab")
		)
		(fp_line
			(start 0.67945 0.3048)
			(end 0.67945 -0.305054)
			(stroke
				(width 0.1)
				(type default)
			)
			(layer "B.Fab")
		)
		(fp_line
			(start 0.12065 0.3048)
			(end 0.67945 0.3048)
			(stroke
				(width 0.1)
				(type default)
			)
			(layer "B.Fab")
		)
		(fp_line
			(start -0.120396 0.3048)
			(end -0.120396 0.2794)
			(stroke
				(width 0.1)
				(type default)
			)
			(layer "B.Fab")
		)
		(fp_line
			(start -0.67945 0.3048)
			(end -0.120396 0.3048)
			(stroke
				(width 0.1)
				(type default)
			)
			(layer "B.Fab")
		)
		(pad "1" smd circle
			(at 0.40005 0 270)
			(size 0 0)
			(layers "B.Cu" "B.Mask" "B.Paste")
			(net "SMB_BMC_ALERT10_N")
		)
		(pad "2" smd circle
			(at -0.40005 0 270)
			(size 0 0)
			(layers "B.Cu" "B.Mask" "B.Paste")
			(net "SMB_BMC_ALERT10_R_N")
		)
	)
)
